# SCM (Grand Teton) — schematic netlist excerpt (pin names and nets, part order shuffled) for the footprints in the layout excerpt that follows; sources: Cadence DE-HDL packaged netlist, KiCad conversion of 12092022_DA0F0TMDCD0_F0T_Management_Board_D_brd_V3_OCP.brd

C206  Q_CAP  15PF 50V 5% C0G  pkg 0402  page 23 : A = V_DACG ; B = GND
C255  Q_CAP  0.1UF 25V 10% X7R  pkg 0402  page 44 : A = P3V3_AUX ; B = GND

(kicad_pcb
	(version 20260206)
	(generator "pcbnew")
	(generator_version "10.0")
	(general
		(thickness 1.6)
		(legacy_teardrops no)
	)
	(paper "A4")
	(title_block
		(title "12092022_DA0F0TMDCD0_F0T_Management_Board_D_brd_V3_OCP.brd")
		(comment 1 "Grand Teton / footprints 1312-1313 of 1440")
	)
	(layers
		(0 "F.Cu" signal "TOP")
		(4 "In1.Cu" signal "GND")
		(6 "In2.Cu" signal "IN1")
		(8 "In3.Cu" signal "GND1")
		(10 "In4.Cu" signal "IN2")
		(12 "In5.Cu" signal "VCC")
		(14 "In6.Cu" signal "VCC1")
		(16 "In7.Cu" signal "IN3")
		(18 "In8.Cu" signal "GND2")
		(20 "In9.Cu" signal "IN4")
		(22 "In10.Cu" signal "GND3")
		(2 "B.Cu" signal "BOTTOM")
		(9 "F.Adhes" user "F.Adhesive")
		(11 "B.Adhes" user "B.Adhesive")
		(13 "F.Paste" user "Package Geometry/Pastemask Top")
		(15 "B.Paste" user "Package Geometry/Pastemask Bottom")
		(5 "F.SilkS" user "Ref Des/Silkscreen Top")
		(7 "B.SilkS" user "Ref Des/Silkscreen Bottom")
		(1 "F.Mask" user "Board Geometry/Soldermask Top")
		(3 "B.Mask" user "Board Geometry/Soldermask Bottom")
		(17 "Dwgs.User" user "User.Drawings")
		(19 "Cmts.User" user "User.Comments")
		(21 "Eco1.User" user "User.Eco1")
		(23 "Eco2.User" user "User.Eco2")
		(25 "Edge.Cuts" user "Board Geometry/Outline")
		(27 "Margin" user)
		(31 "F.CrtYd" user "Package Geometry/Place Bound Top")
		(29 "B.CrtYd" user "Package Geometry/Place Bound Bottom")
		(35 "F.Fab" user "Ref Des/Assembly Top")
		(33 "B.Fab" user "Ref Des/Assembly Bottom")
	)
	(footprint ""
		(layer "B.Cu")
		(at 28.3464 -30.35935 -90)
		(property "Reference" "C206"
			(at 0 0 90)
			(layer "B.SilkS")
			(hide yes)
			(effects
				(font
					(size 1.27 1.27)
				)
				(justify mirror)
			)
		)
		(property "Value" ""
			(at 0 0 90)
			(layer "B.Fab")
			(effects
				(font
					(size 1.27 1.27)
				)
				(justify mirror)
			)
		)
		(duplicate_pad_numbers_are_jumpers no)
		(fp_line
			(start -0.7874 0.4064)
			(end 0.7874 0.4064)
			(stroke
				(width 0.1524)
				(type default)
			)
			(layer "B.SilkS")
		)
		(fp_line
			(start 0.7874 0.4064)
			(end 0.7874 -0.4064)
			(stroke
				(width 0.1524)
				(type default)
			)
			(layer "B.SilkS")
		)
		(fp_line
			(start -0.7874 -0.4064)
			(end -0.7874 0.4064)
			(stroke
				(width 0.1524)
				(type default)
			)
			(layer "B.SilkS")
		)
		(fp_line
			(start 0.7874 -0.4064)
			(end -0.7874 -0.4064)
			(stroke
				(width 0.1524)
				(type default)
			)
			(layer "B.SilkS")
		)
		(fp_line
			(start -0.67945 0.3048)
			(end -0.120396 0.3048)
			(stroke
				(width 0.1)
				(type default)
			)
			(layer "B.Fab")
		)
		(fp_line
			(start -0.120396 0.3048)
			(end -0.120396 0.2794)
			(stroke
				(width 0.1)
				(type default)
			)
			(layer "B.Fab")
		)
		(fp_line
			(start 0.12065 0.3048)
			(end 0.67945 0.3048)
			(stroke
				(width 0.1)
				(type default)
			)
			(layer "B.Fab")
		)
		(fp_line
			(start 0.67945 0.3048)
			(end 0.67945 -0.305054)
			(stroke
				(width 0.1)
				(type default)
			)
			(layer "B.Fab")
		)
		(fp_line
			(start -0.120396 0.2794)
			(end 0.12065 0.2794)
			(stroke
				(width 0.1)
				(type default)
			)
			(layer "B.Fab")
		)
		(fp_line
			(start 0.12065 0.2794)
			(end 0.12065 0.3048)
			(stroke
				(width 0.1)
				(type default)
			)
			(layer "B.Fab")
		)
		(fp_line
			(start -0.12065 -0.2794)
			(end -0.12065 -0.3048)
			(stroke
				(width 0.1)
				(type default)
			)
			(layer "B.Fab")
		)
		(fp_line
			(start 0.12065 -0.2794)
			(end -0.12065 -0.2794)
			(stroke
				(width 0.1)
				(type default)
			)
			(layer "B.Fab")
		)
		(fp_line
			(start -0.67945 -0.3048)
			(end -0.67945 0.3048)
			(stroke
				(width 0.1)
				(type default)
			)
			(layer "B.Fab")
		)
		(fp_line
			(start -0.12065 -0.3048)
			(end -0.67945 -0.3048)
			(stroke
				(width 0.1)
				(type default)
			)
			(layer "B.Fab")
		)
		(fp_line
			(start 0.12065 -0.305054)
			(end 0.12065 -0.2794)
			(stroke
				(width 0.1)
				(type default)
			)
			(layer "B.Fab")
		)
		(fp_line
			(start 0.67945 -0.305054)
			(end 0.12065 -0.305054)
			(stroke
				(width 0.1)
				(type default)
			)
			(layer "B.Fab")
		)
		(pad "1" smd circle
			(at 0.40005 0 90)
			(size 0 0)
			(layers "B.Cu" "B.Mask" "B.Paste")
			(net "V_DACG")
		)
		(pad "2" smd circle
			(at -0.40005 0 90)
			(size 0 0)
			(layers "B.Cu" "B.Mask" "B.Paste")
			(net "GND")
		)
	)
	(footprint ""
		(layer "B.Cu")
		(at 53.4924 -77.9018 -90)
		(property "Reference" "C255"
			(at 0 0 90)
			(layer "B.SilkS")
			(hide yes)
			(effects
				(font
					(size 1.27 1.27)
				)
				(justify mirror)
			)
		)
		(property "Value" ""
			(at 0 0 90)
			(layer "B.Fab")
			(effects
				(font
					(size 1.27 1.27)
				)
				(justify mirror)
			)
		)
		(duplicate_pad_numbers_are_jumpers no)
		(fp_line
			(start -0.7874 0.4064)
			(end 0.7874 0.4064)
			(stroke
				(width 0.1524)
				(type default)
			)
			(layer "B.SilkS")
		)
		(fp_line
			(start 0.7874 0.4064)
			(end 0.7874 -0.4064)
			(stroke
				(width 0.1524)
				(type default)
			)
			(layer "B.SilkS")
		)
		(fp_line
			(start -0.7874 -0.4064)
			(end -0.7874 0.4064)
			(stroke
				(width 0.1524)
				(type default)
			)
			(layer "B.SilkS")
		)
		(fp_line
			(start 0.7874 -0.4064)
			(end -0.7874 -0.4064)
			(stroke
				(width 0.1524)
				(type default)
			)
			(layer "B.SilkS")
		)
		(fp_line
			(start -0.67945 0.3048)
			(end -0.120396 0.3048)
			(stroke
				(width 0.1)
				(type default)
			)
			(layer "B.Fab")
		)
		(fp_line
			(start -0.120396 0.3048)
			(end -0.120396 0.2794)
			(stroke
				(width 0.1)
				(type default)
			)
			(layer "B.Fab")
		)
		(fp_line
			(start 0.12065 0.3048)
			(end 0.67945 0.3048)
			(stroke
				(width 0.1)
				(type default)
			)
			(layer "B.Fab")
		)
		(fp_line
			(start 0.67945 0.3048)
			(end 0.67945 -0.305054)
			(stroke
				(width 0.1)
				(type default)
			)
			(layer "B.Fab")
		)
		(fp_line
			(start -0.120396 0.2794)
			(end 0.12065 0.2794)
			(stroke
				(width 0.1)
				(type default)
			)
			(layer "B.Fab")
		)
		(fp_line
			(start 0.12065 0.2794)
			(end 0.12065 0.3048)
			(stroke
				(width 0.1)
				(type default)
			)
			(layer "B.Fab")
		)
		(fp_line
			(start -0.12065 -0.2794)
			(end -0.12065 -0.3048)
			(stroke
				(width 0.1)
				(type default)
			)
			(layer "B.Fab")
		)
		(fp_line
			(start 0.12065 -0.2794)
			(end -0.12065 -0.2794)
			(stroke
				(width 0.1)
				(type default)
			)
			(layer "B.Fab")
		)
		(fp_line
			(start -0.67945 -0.3048)
			(end -0.67945 0.3048)
			(stroke
				(width 0.1)
				(type default)
			)
			(layer "B.Fab")
		)
		(fp_line
			(start -0.12065 -0.3048)
			(end -0.67945 -0.3048)
			(stroke
				(width 0.1)
				(type default)
			)
			(layer "B.Fab")
		)
		(fp_line
			(start 0.12065 -0.305054)
			(end 0.12065 -0.2794)
			(stroke
				(width 0.1)
				(type default)
			)
			(layer "B.Fab")
		)
		(fp_line
			(start 0.67945 -0.305054)
			(end 0.12065 -0.305054)
			(stroke
				(width 0.1)
				(type default)
			)
			(layer "B.Fab")
		)
		(pad "1" smd circle
			(at 0.40005 0 90)
			(size 0 0)
			(layers "B.Cu" "B.Mask" "B.Paste")
			(net "P3V3_AUX")
		)
		(pad "2" smd circle
			(at -0.40005 0 90)
			(size 0 0)
			(layers "B.Cu" "B.Mask" "B.Paste")
			(net "GND")
		)
	)
)
